Wiwynn ST700G2 (Bryce Canyon Storage) Design Checklist Presentation 
OCP Principles  
Efficiency –  
Scale –  
Openness–  
Impact –  
See long from principles http://opencompute.org/about/mission-and-principles/  
©  2017 Wiwynn Intellectual Property. All rights reserved. Wiwynn, Globe logo are registered trademarks and service marks of 
Wiwynn Intellectual Property and/or Wiwynn affiliated companies. All other marks are the property of their respective owners.  
 
